(kicad_pcb
	(version 20241229)
	(generator "pcbnew")
	(generator_version "9.0")
	(general
		(thickness 1.6642)
		(legacy_teardrops no)
	)
	(paper "A3")
	(title_block
		(title "PolarFire SoM")
		(date "2025-07-22")
		(rev "1.1.4")
		(company "Antmicro Ltd")
		(comment 1 "www.antmicro.com")
		(comment 9 "footprints 435-438 of 470")
	)
	(layers
		(0 "F.Cu" mixed)
		(4 "In1.Cu" power)
		(6 "In2.Cu" signal)
		(8 "In3.Cu" power)
		(10 "In4.Cu" signal)
		(12 "In5.Cu" power)
		(14 "In6.Cu" power)
		(16 "In7.Cu" signal)
		(18 "In8.Cu" power)
		(20 "In9.Cu" signal)
		(22 "In10.Cu" power)
		(24 "In11.Cu" signal)
		(26 "In12.Cu" signal)
		(2 "B.Cu" mixed)
		(9 "F.Adhes" user "F.Adhesive")
		(11 "B.Adhes" user "B.Adhesive")
		(13 "F.Paste" user)
		(15 "B.Paste" user)
		(5 "F.SilkS" user "F.Silkscreen")
		(7 "B.SilkS" user "B.Silkscreen")
		(1 "F.Mask" user)
		(3 "B.Mask" user)
		(17 "Dwgs.User" user "User.Drawings")
		(19 "Cmts.User" user "User.Comments")
		(21 "Eco1.User" user "User.Eco1")
		(23 "Eco2.User" user "User.Eco2")
		(25 "Edge.Cuts" user)
		(27 "Margin" user)
		(31 "F.CrtYd" user "F.Courtyard")
		(29 "B.CrtYd" user "B.Courtyard")
		(35 "F.Fab" user)
		(33 "B.Fab" user)
	)
	(footprint "antmicro-footprints:SOT-523"
		(layer "B.Cu")
		(at 222.08 129.9 180)
		(property "Reference" "Q5"
			(at 0.23 0.3 180)
			(layer "B.SilkS")
			(effects
				(font
					(size 0.7 0.7)
					(thickness 0.15)
				)
				(justify left bottom mirror)
			)
		)
		(property "Value" "DMG1012T-7"
			(at 0.1 -1.824 0)
			(layer "B.Fab")
			(hide yes)
			(effects
				(font
					(size 0.7 0.7)
					(thickness 0.15)
				)
				(justify left bottom mirror)
			)
		)
		(property "Datasheet" "https://www.diodes.com/assets/Datasheets/ds31783.pdf"
			(at 0 0 180)
			(layer "F.Fab")
			(hide yes)
			(effects
				(font
					(size 1.27 1.27)
					(thickness 0.15)
				)
			)
		)
		(property "Description" "Power MOSFET, N Channel, 20 V, 630 mA, 0.3 ohm, SOT-523, Surface Mount"
			(at 0 0 180)
			(layer "F.Fab")
			(hide yes)
			(effects
				(font
					(size 1.27 1.27)
					(thickness 0.15)
				)
			)
		)
		(property "Author" "Antmicro"
			(at 444.16 259.8 0)
			(layer "B.Fab")
			(hide yes)
			(effects
				(font
					(size 1 1)
					(thickness 0.15)
				)
				(justify mirror)
			)
		)
		(property "License" "Apache-2.0"
			(at 444.16 259.8 0)
			(layer "B.Fab")
			(hide yes)
			(effects
				(font
					(size 1 1)
					(thickness 0.15)
				)
				(justify mirror)
			)
		)
		(property "MPN" "DMG1012T-7"
			(at 444.16 259.8 0)
			(layer "B.Fab")
			(hide yes)
			(effects
				(font
					(size 1 1)
					(thickness 0.15)
				)
				(justify mirror)
			)
		)
		(property "Manufacturer" "Diodes Incorporated"
			(at 444.16 259.8 0)
			(layer "B.Fab")
			(hide yes)
			(effects
				(font
					(size 1 1)
					(thickness 0.15)
				)
				(justify mirror)
			)
		)
		(property "Public" ""
			(at 444.16 259.8 0)
			(layer "B.Fab")
			(hide yes)
			(effects
				(font
					(size 1 1)
					(thickness 0.15)
				)
				(justify mirror)
			)
		)
		(sheetname "/FPGA GPIO/")
		(sheetfile "fpga-gpio.kicad_sch")
		(attr smd)
		(fp_line
			(start -0.277 0.551)
			(end -0.277 0.75)
			(stroke
				(width 0.15)
				(type solid)
			)
			(layer "B.SilkS")
		)
		(fp_line
			(start -0.725 0.551)
			(end -0.277 0.551)
			(stroke
				(width 0.15)
				(type solid)
			)
			(layer "B.SilkS")
		)
		(fp_line
			(start -0.927 0.351)
			(end -0.725 0.551)
			(stroke
				(width 0.15)
				(type solid)
			)
			(layer "B.SilkS")
		)
		(fp_line
			(start -0.927 0.051)
			(end -0.927 0.351)
			(stroke
				(width 0.15)
				(type solid)
			)
			(layer "B.SilkS")
		)
		(fp_circle
			(center -0.9652 -0.9652)
			(end -0.9152 -0.9652)
			(stroke
				(width 0.15)
				(type solid)
			)
			(fill yes)
			(layer "B.SilkS")
		)
		(fp_line
			(start 1.1 1.16)
			(end 1.1 -1.15)
			(stroke
				(width 0.05)
				(type solid)
			)
			(layer "B.CrtYd")
		)
		(fp_line
			(start -1.12 1.16)
			(end 1.1 1.16)
			(stroke
				(width 0.05)
				(type solid)
			)
			(layer "B.CrtYd")
		)
		(fp_line
			(start -1.12 1.16)
			(end -1.12 -1.15)
			(stroke
				(width 0.05)
				(type solid)
			)
			(layer "B.CrtYd")
		)
		(fp_line
			(start -1.12 -1.15)
			(end 1.1 -1.15)
			(stroke
				(width 0.05)
				(type solid)
			)
			(layer "B.CrtYd")
		)
		(fp_line
			(start 0.8 0.425)
			(end 0.8 -0.424)
			(stroke
				(width 0.15)
				(type solid)
			)
			(layer "B.Fab")
		)
		(fp_line
			(start 0.8 0.425)
			(end -0.652 0.425)
			(stroke
				(width 0.15)
				(type solid)
			)
			(layer "B.Fab")
		)
		(fp_line
			(start 0.8 -0.424)
			(end -0.802 -0.424)
			(stroke
				(width 0.15)
				(type solid)
			)
			(layer "B.Fab")
		)
		(fp_line
			(start -0.652 0.425)
			(end -0.802 0.276)
			(stroke
				(width 0.15)
				(type solid)
			)
			(layer "B.Fab")
		)
		(fp_line
			(start -0.802 0.276)
			(end -0.802 -0.424)
			(stroke
				(width 0.15)
				(type solid)
			)
			(layer "B.Fab")
		)
		(fp_circle
			(center -0.9652 -0.9652)
			(end -0.9144 -0.9652)
			(stroke
				(width 0.15)
				(type solid)
			)
			(fill no)
			(layer "B.Fab")
		)
		(fp_text user "${REFERENCE}"
			(at -1.12 -3.824 0)
			(layer "B.Fab")
			(effects
				(font
					(size 0.7 0.7)
					(thickness 0.15)
				)
				(justify left bottom mirror)
			)
		)
		(fp_text user "Author: Antmicro"
			(at -1.12 -6.224 0)
			(layer "B.Fab")
			(effects
				(font
					(size 0.7 0.7)
					(thickness 0.15)
				)
				(justify left bottom mirror)
			)
		)
		(fp_text user "License: Apache-2.0"
			(at -1.12 -5.024 0)
			(layer "B.Fab")
			(effects
				(font
					(size 0.7 0.7)
					(thickness 0.15)
				)
				(justify left bottom mirror)
			)
		)
		(pad "1" smd rect
			(at -0.5 -0.65 180)
			(size 0.4 0.51)
			(layers "B.Cu" "B.Mask" "B.Paste")
			(net 224 "/FPGA GPIO/USER_LED_B")
			(pinfunction "G")
			(pintype "input")
		)
		(pad "2" smd rect
			(at 0.498 -0.65 180)
			(size 0.4 0.51)
			(layers "B.Cu" "B.Mask" "B.Paste")
			(net 417 "GND")
			(pinfunction "S")
			(pintype "passive")
		)
		(pad "3" smd rect
			(at 0 0.652 180)
			(size 0.4 0.51)
			(layers "B.Cu" "B.Mask" "B.Paste")
			(net 540 "Net-(Q5-D)")
			(pinfunction "D")
			(pintype "passive")
		)
	)
	(footprint "antmicro-footprints:C_0402_1005Metric"
		(layer "B.Cu")
		(at 215.1925 129.668 180)
		(descr "Capacitor SMD 0402")
		(tags "capacitor SMD 0402")
		(property "Reference" "C79"
			(at -3.0475 -0.472 0)
			(layer "B.SilkS")
			(effects
				(font
					(size 0.7 0.7)
					(thickness 0.15)
				)
				(justify left bottom mirror)
			)
		)
		(property "Value" "C_100n_0402"
			(at -1.022927 -2.155213 0)
			(layer "B.Fab")
			(hide yes)
			(effects
				(font
					(size 0.7 0.7)
					(thickness 0.15)
				)
				(justify left bottom mirror)
			)
		)
		(property "Datasheet" "https://www.murata.com/products/productdetail?partno=GRM155R61H104KE14%23"
			(at 0 0 180)
			(layer "F.Fab")
			(hide yes)
			(effects
				(font
					(size 1.27 1.27)
					(thickness 0.15)
				)
			)
		)
		(property "Description" "SMD Multilayer Ceramic Capacitor, 0.1 µF, 50 V, 0402 [1005 Metric], ± 10%, X5R, GRM Series"
			(at 0 0 180)
			(layer "F.Fab")
			(hide yes)
			(effects
				(font
					(size 1.27 1.27)
					(thickness 0.15)
				)
			)
		)
		(property "Author" "Antmicro"
			(at 430.385 259.336 0)
			(layer "B.Fab")
			(hide yes)
			(effects
				(font
					(size 1 1)
					(thickness 0.15)
				)
				(justify mirror)
			)
		)
		(property "Dielectric" "X5R"
			(at 430.385 259.336 0)
			(layer "B.Fab")
			(hide yes)
			(effects
				(font
					(size 1 1)
					(thickness 0.15)
				)
				(justify mirror)
			)
		)
		(property "License" "Apache-2.0"
			(at 430.385 259.336 0)
			(layer "B.Fab")
			(hide yes)
			(effects
				(font
					(size 1 1)
					(thickness 0.15)
				)
				(justify mirror)
			)
		)
		(property "MPN" "GRM155R61H104KE14D"
			(at 430.385 259.336 0)
			(layer "B.Fab")
			(hide yes)
			(effects
				(font
					(size 1 1)
					(thickness 0.15)
				)
				(justify mirror)
			)
		)
		(property "Manufacturer" "Murata"
			(at 430.385 259.336 0)
			(layer "B.Fab")
			(hide yes)
			(effects
				(font
					(size 1 1)
					(thickness 0.15)
				)
				(justify mirror)
			)
		)
		(property "Public" ""
			(at 430.385 259.336 0)
			(layer "B.Fab")
			(hide yes)
			(effects
				(font
					(size 1 1)
					(thickness 0.15)
				)
				(justify mirror)
			)
		)
		(property "Val" "100n"
			(at 430.385 259.336 0)
			(layer "B.Fab")
			(hide yes)
			(effects
				(font
					(size 1 1)
					(thickness 0.15)
				)
				(justify mirror)
			)
		)
		(property "Voltage" "50V"
			(at 430.385 259.336 0)
			(layer "B.Fab")
			(hide yes)
			(effects
				(font
					(size 1 1)
					(thickness 0.15)
				)
				(justify mirror)
			)
		)
		(sheetname "/Memory/")
		(sheetfile "memory.kicad_sch")
		(attr smd)
		(fp_rect
			(start -0.925 0.47)
			(end 0.925 -0.47)
			(stroke
				(width 0.05)
				(type default)
			)
			(fill no)
			(layer "B.CrtYd")
		)
		(fp_line
			(start 0.504 0.25)
			(end 0.504 -0.248)
			(stroke
				(width 0.15)
				(type solid)
			)
			(layer "B.Fab")
		)
		(fp_line
			(start 0.504 -0.248)
			(end -0.494 -0.248)
			(stroke
				(width 0.15)
				(type solid)
			)
			(layer "B.Fab")
		)
		(fp_line
			(start -0.494 0.25)
			(end 0.504 0.25)
			(stroke
				(width 0.15)
				(type solid)
			)
			(layer "B.Fab")
		)
		(fp_line
			(start -0.494 -0.248)
			(end -0.494 0.25)
			(stroke
				(width 0.15)
				(type solid)
			)
			(layer "B.Fab")
		)
		(fp_text user "Author: Antmicro"
			(at -0.939 -3.399 0)
			(layer "B.Fab")
			(effects
				(font
					(size 0.7 0.7)
					(thickness 0.15)
				)
				(justify left bottom mirror)
			)
		)
		(fp_text user "${REFERENCE}"
			(at -0.939 -4.599 0)
			(layer "B.Fab")
			(effects
				(font
					(size 0.7 0.7)
					(thickness 0.15)
				)
				(justify left bottom mirror)
			)
		)
		(fp_text user "License: Apache-2.0"
			(at -0.939 -5.799 0)
			(layer "B.Fab")
			(effects
				(font
					(size 0.7 0.7)
					(thickness 0.15)
				)
				(justify left bottom mirror)
			)
		)
		(pad "1" smd roundrect
			(at -0.48 0 180)
			(size 0.59 0.64)
			(layers "B.Cu" "B.Mask" "B.Paste")
			(roundrect_rratio 0.25)
			(net 417 "GND")
			(pintype "passive")
		)
		(pad "2" smd roundrect
			(at 0.48 0 180)
			(size 0.59 0.64)
			(layers "B.Cu" "B.Mask" "B.Paste")
			(roundrect_rratio 0.25)
			(net 137 "SD_VDD")
			(pintype "passive")
		)
	)
	(footprint "antmicro-footprints:R_0402_1005Metric"
		(layer "B.Cu")
		(at 218.975 134.775)
		(descr "Resistor SMD 0402")
		(tags "resistor SMD 0402")
		(property "Reference" "R10"
			(at -0.775 0.45 180)
			(layer "B.SilkS")
			(effects
				(font
					(size 0.7 0.7)
					(thickness 0.15)
				)
				(justify left bottom mirror)
			)
		)
		(property "Value" "R_10k_0402"
			(at -1.011843 -1.772047 180)
			(layer "B.Fab")
			(hide yes)
			(effects
				(font
					(size 0.7 0.7)
					(thickness 0.15)
				)
				(justify left bottom mirror)
			)
		)
		(property "Datasheet" "https://www.bourns.com/docs/product-datasheets/cr.pdf"
			(at 0 0 0)
			(layer "F.Fab")
			(hide yes)
			(effects
				(font
					(size 1.27 1.27)
					(thickness 0.15)
				)
			)
		)
		(property "Description" "SMD Chip Resistor, 10 kohm, ± 1%, 62.5 mW, 0402 [1005 Metric], Thick Film, General Purpose"
			(at 0 0 0)
			(layer "F.Fab")
			(hide yes)
			(effects
				(font
					(size 1.27 1.27)
					(thickness 0.15)
				)
			)
		)
		(property "Author" "Antmicro"
			(at 0 0 0)
			(layer "B.Fab")
			(hide yes)
			(effects
				(font
					(size 1 1)
					(thickness 0.15)
				)
				(justify mirror)
			)
		)
		(property "License" "Apache-2.0"
			(at 0 0 0)
			(layer "B.Fab")
			(hide yes)
			(effects
				(font
					(size 1 1)
					(thickness 0.15)
				)
				(justify mirror)
			)
		)
		(property "MPN" "CR0402-FX-1002GLF"
			(at 0 0 0)
			(layer "B.Fab")
			(hide yes)
			(effects
				(font
					(size 1 1)
					(thickness 0.15)
				)
				(justify mirror)
			)
		)
		(property "Manufacturer" "Bourns"
			(at 0 0 0)
			(layer "B.Fab")
			(hide yes)
			(effects
				(font
					(size 1 1)
					(thickness 0.15)
				)
				(justify mirror)
			)
		)
		(property "Public" ""
			(at 0 0 0)
			(layer "B.Fab")
			(hide yes)
			(effects
				(font
					(size 1 1)
					(thickness 0.15)
				)
				(justify mirror)
			)
		)
		(property "Tolerance" "1%"
			(at 0 0 0)
			(layer "B.Fab")
			(hide yes)
			(effects
				(font
					(size 1 1)
					(thickness 0.15)
				)
				(justify mirror)
			)
		)
		(property "Val" "10k"
			(at 0 0 0)
			(layer "B.Fab")
			(hide yes)
			(effects
				(font
					(size 1 1)
					(thickness 0.15)
				)
				(justify mirror)
			)
		)
		(sheetname "/Supply/")
		(sheetfile "supply.kicad_sch")
		(attr smd)
		(fp_rect
			(start -0.925 0.47)
			(end 0.925 -0.47)
			(stroke
				(width 0.05)
				(type default)
			)
			(fill no)
			(layer "B.CrtYd")
		)
		(fp_rect
			(start -0.5 0.25)
			(end 0.5 -0.25)
			(stroke
				(width 0.15)
				(type solid)
			)
			(fill no)
			(layer "B.Fab")
		)
		(fp_text user "License: Apache-2.0"
			(at -0.95 -5.169 180)
			(layer "B.Fab")
			(effects
				(font
					(size 0.7 0.7)
					(thickness 0.15)
				)
				(justify left bottom mirror)
			)
		)
		(fp_text user "${REFERENCE}"
			(at -0.95 -3.168 180)
			(layer "B.Fab")
			(effects
				(font
					(size 0.7 0.7)
					(thickness 0.15)
				)
				(justify left bottom mirror)
			)
		)
		(fp_text user "Author: Antmicro"
			(at -0.95 -4.169 180)
			(layer "B.Fab")
			(effects
				(font
					(size 0.7 0.7)
					(thickness 0.15)
				)
				(justify left bottom mirror)
			)
		)
		(pad "1" smd roundrect
			(at -0.48 0)
			(size 0.59 0.64)
			(layers "B.Cu" "B.Mask" "B.Paste")
			(roundrect_rratio 0.25)
			(net 334 "VREF_FLAG")
			(pintype "passive")
		)
		(pad "2" smd roundrect
			(at 0.48 0)
			(size 0.59 0.64)
			(layers "B.Cu" "B.Mask" "B.Paste")
			(roundrect_rratio 0.25)
			(net 296 "Net-(R10-Pad2)")
			(pintype "passive")
		)
	)
	(footprint "antmicro-footprints:C_0402_1005Metric"
		(layer "B.Cu")
		(at 219.9 122.8)
		(descr "Capacitor SMD 0402")
		(tags "capacitor SMD 0402")
		(property "Reference" "C195"
			(at 6.55 3.85 0)
			(layer "B.SilkS")
			(effects
				(font
					(size 0.7 0.7)
					(thickness 0.15)
				)
				(justify right bottom mirror)
			)
		)
		(property "Value" "C_10n_0402"
			(at -1.022927 -2.155213 0)
			(layer "B.Fab")
			(hide yes)
			(effects
				(font
					(size 0.7 0.7)
					(thickness 0.15)
				)
				(justify right bottom mirror)
			)
		)
		(property "Datasheet" "https://www.murata.com/products/productdetail?partno=GRM155R71H103KA88%23"
			(at 0 0 0)
			(layer "F.Fab")
			(hide yes)
			(effects
				(font
					(size 1.27 1.27)
					(thickness 0.15)
				)
			)
		)
		(property "Description" "SMD Multilayer Ceramic Capacitor, 10000 pF, 50 V, 0402 [1005 Metric], ± 10%, X7R, GRM Series"
			(at 0 0 0)
			(layer "F.Fab")
			(hide yes)
			(effects
				(font
					(size 1.27 1.27)
					(thickness 0.15)
				)
			)
		)
		(property "Author" "Antmicro"
			(at 0 0 0)
			(layer "B.Fab")
			(hide yes)
			(effects
				(font
					(size 1 1)
					(thickness 0.15)
				)
				(justify mirror)
			)
		)
		(property "Dielectric" "X7R"
			(at 0 0 0)
			(layer "B.Fab")
			(hide yes)
			(effects
				(font
					(size 1 1)
					(thickness 0.15)
				)
				(justify mirror)
			)
		)
		(property "License" "Apache-2.0"
			(at 0 0 0)
			(layer "B.Fab")
			(hide yes)
			(effects
				(font
					(size 1 1)
					(thickness 0.15)
				)
				(justify mirror)
			)
		)
		(property "MPN" "GRM155R71H103KA88D"
			(at 0 0 0)
			(layer "B.Fab")
			(hide yes)
			(effects
				(font
					(size 1 1)
					(thickness 0.15)
				)
				(justify mirror)
			)
		)
		(property "Manufacturer" "Murata"
			(at 0 0 0)
			(layer "B.Fab")
			(hide yes)
			(effects
				(font
					(size 1 1)
					(thickness 0.15)
				)
				(justify mirror)
			)
		)
		(property "Public" ""
			(at 0 0 0)
			(layer "B.Fab")
			(hide yes)
			(effects
				(font
					(size 1 1)
					(thickness 0.15)
				)
				(justify mirror)
			)
		)
		(property "Val" "10n"
			(at 0 0 0)
			(layer "B.Fab")
			(hide yes)
			(effects
				(font
					(size 1 1)
					(thickness 0.15)
				)
				(justify mirror)
			)
		)
		(property "Voltage" "50V"
			(at 0 0 0)
			(layer "B.Fab")
			(hide yes)
			(effects
				(font
					(size 1 1)
					(thickness 0.15)
				)
				(justify mirror)
			)
		)
		(sheetname "/Ethernet/")
		(sheetfile "ethernet.kicad_sch")
		(attr smd)
		(fp_rect
			(start -0.925 0.47)
			(end 0.925 -0.47)
			(stroke
				(width 0.05)
				(type default)
			)
			(fill no)
			(layer "B.CrtYd")
		)
		(fp_line
			(start -0.494 -0.248)
			(end -0.494 0.25)
			(stroke
				(width 0.15)
				(type solid)
			)
			(layer "B.Fab")
		)
		(fp_line
			(start -0.494 0.25)
			(end 0.504 0.25)
			(stroke
				(width 0.15)
				(type solid)
			)
			(layer "B.Fab")
		)
		(fp_line
			(start 0.504 -0.248)
			(end -0.494 -0.248)
			(stroke
				(width 0.15)
				(type solid)
			)
			(layer "B.Fab")
		)
		(fp_line
			(start 0.504 0.25)
			(end 0.504 -0.248)
			(stroke
				(width 0.15)
				(type solid)
			)
			(layer "B.Fab")
		)
		(fp_text user "License: Apache-2.0"
			(at -0.939 -5.799 180)
			(layer "B.Fab")
			(effects
				(font
					(size 0.7 0.7)
					(thickness 0.15)
				)
				(justify left bottom mirror)
			)
		)
		(fp_text user "Author: Antmicro"
			(at -0.939 -3.399 180)
			(layer "B.Fab")
			(effects
				(font
					(size 0.7 0.7)
					(thickness 0.15)
				)
				(justify left bottom mirror)
			)
		)
		(fp_text user "${REFERENCE}"
			(at -0.939 -4.599 180)
			(layer "B.Fab")
			(effects
				(font
					(size 0.7 0.7)
					(thickness 0.15)
				)
				(justify left bottom mirror)
			)
		)
		(pad "1" smd roundrect
			(at -0.48 0)
			(size 0.59 0.64)
			(layers "B.Cu" "B.Mask" "B.Paste")
			(roundrect_rratio 0.25)
			(net 417 "GND")
			(pintype "passive")
		)
		(pad "2" smd roundrect
			(at 0.48 0)
			(size 0.59 0.64)
			(layers "B.Cu" "B.Mask" "B.Paste")
			(roundrect_rratio 0.25)
			(net 418 "+2V5")
			(pintype "passive")
		)
	)
)
